# T6G (Grand Teton) — schematic netlist excerpt (pin names and nets, part order shuffled) for the footprints in the layout excerpt that follows; sources: Cadence DE-HDL packaged netlist, KiCad conversion of 04192023_DAF0TMB3IC0_F0TG_MB_C_brd_V02_OCP.brd

PC87_1  Q_CAP  1UF 25V 10% X6S  pkg C0402  page 201 : A = SW_P12V_AUX_PVDDCR_CPU1_P0_FLT ; B = GND
PC230  Q_CAPP  390UF 2.5V 20% ALUM  pkg SMLF  page 208 : A = PVDD11_S3_P0 ; B = GND
C6521  Q_CAP_DIFFBUS  DIFF BUS_0.22UF 6.3V 20% X6S  pkg C0201  page 275 : \1\ = P5E_CPU0_P0_TX_BUF_C_DP<10> ; \2\ = P5E_CPU0_P0_TX_BUF_DP<10>

(kicad_pcb
	(version 20260206)
	(generator "pcbnew")
	(generator_version "10.0")
	(general
		(thickness 1.6)
		(legacy_teardrops no)
	)
	(paper "A4")
	(title_block
		(title "04192023_DAF0TMB3IC0_F0TG_MB_C_brd_V02_OCP.brd")
		(comment 1 "Grand Teton / footprints 3893-3895 of 8354")
	)
	(layers
		(0 "F.Cu" signal "TOP")
		(4 "In1.Cu" signal "GND")
		(6 "In2.Cu" signal "IN1")
		(8 "In3.Cu" signal "GND1")
		(10 "In4.Cu" signal "IN2")
		(12 "In5.Cu" signal "GND2")
		(14 "In6.Cu" signal "IN3")
		(16 "In7.Cu" signal "GND3")
		(18 "In8.Cu" signal "VCC")
		(20 "In9.Cu" signal "VCC1")
		(22 "In10.Cu" signal "GND4")
		(24 "In11.Cu" signal "IN4")
		(26 "In12.Cu" signal "GND5")
		(28 "In13.Cu" signal "IN5")
		(30 "In14.Cu" signal "GND6")
		(32 "In15.Cu" signal "IN6")
		(34 "In16.Cu" signal "GND7")
		(2 "B.Cu" signal "BOTTOM")
		(9 "F.Adhes" user "F.Adhesive")
		(11 "B.Adhes" user "B.Adhesive")
		(13 "F.Paste" user "Package Geometry/Pastemask Top")
		(15 "B.Paste" user "Package Geometry/Pastemask Bottom")
		(5 "F.SilkS" user "Ref Des/Silkscreen Top")
		(7 "B.SilkS" user "Ref Des/Silkscreen Bottom")
		(1 "F.Mask" user "Board Geometry/Soldermask Top")
		(3 "B.Mask" user "Board Geometry/Soldermask Bottom")
		(17 "Dwgs.User" user "User.Drawings")
		(19 "Cmts.User" user "User.Comments")
		(21 "Eco1.User" user "User.Eco1")
		(23 "Eco2.User" user "User.Eco2")
		(25 "Edge.Cuts" user "Board Geometry/Outline")
		(27 "Margin" user)
		(31 "F.CrtYd" user "Package Geometry/Place Bound Top")
		(29 "B.CrtYd" user "Package Geometry/Place Bound Bottom")
		(35 "F.Fab" user "Ref Des/Assembly Top")
		(33 "B.Fab" user "Ref Des/Assembly Bottom")
	)
	(footprint ""
		(layer "F.Cu")
		(at 338.693506 -335.12379 -90)
		(property "Reference" "PC87_1"
			(at 0 0 270)
			(layer "F.SilkS")
			(hide yes)
			(effects
				(font
					(size 1.27 1.27)
				)
			)
		)
		(property "Value" ""
			(at 0 0 270)
			(layer "F.Fab")
			(effects
				(font
					(size 1.27 1.27)
				)
			)
		)
		(duplicate_pad_numbers_are_jumpers no)
		(fp_line
			(start -0.7874 0.4064)
			(end -0.7874 -0.4064)
			(stroke
				(width 0.1524)
				(type default)
			)
			(layer "F.SilkS")
		)
		(fp_line
			(start 0.7874 0.4064)
			(end -0.7874 0.4064)
			(stroke
				(width 0.1524)
				(type default)
			)
			(layer "F.SilkS")
		)
		(fp_line
			(start -0.7874 -0.4064)
			(end 0.7874 -0.4064)
			(stroke
				(width 0.1524)
				(type default)
			)
			(layer "F.SilkS")
		)
		(fp_line
			(start 0.7874 -0.4064)
			(end 0.7874 0.4064)
			(stroke
				(width 0.1524)
				(type default)
			)
			(layer "F.SilkS")
		)
		(fp_line
			(start -0.67945 0.3048)
			(end -0.67945 -0.305054)
			(stroke
				(width 0.1)
				(type default)
			)
			(layer "F.Fab")
		)
		(fp_line
			(start -0.12065 0.3048)
			(end -0.67945 0.3048)
			(stroke
				(width 0.1)
				(type default)
			)
			(layer "F.Fab")
		)
		(fp_line
			(start 0.120396 0.3048)
			(end 0.120396 0.2794)
			(stroke
				(width 0.1)
				(type default)
			)
			(layer "F.Fab")
		)
		(fp_line
			(start 0.67945 0.3048)
			(end 0.120396 0.3048)
			(stroke
				(width 0.1)
				(type default)
			)
			(layer "F.Fab")
		)
		(fp_line
			(start -0.12065 0.2794)
			(end -0.12065 0.3048)
			(stroke
				(width 0.1)
				(type default)
			)
			(layer "F.Fab")
		)
		(fp_line
			(start 0.120396 0.2794)
			(end -0.12065 0.2794)
			(stroke
				(width 0.1)
				(type default)
			)
			(layer "F.Fab")
		)
		(fp_line
			(start -0.12065 -0.2794)
			(end 0.12065 -0.2794)
			(stroke
				(width 0.1)
				(type default)
			)
			(layer "F.Fab")
		)
		(fp_line
			(start 0.12065 -0.2794)
			(end 0.12065 -0.3048)
			(stroke
				(width 0.1)
				(type default)
			)
			(layer "F.Fab")
		)
		(fp_line
			(start 0.12065 -0.3048)
			(end 0.67945 -0.3048)
			(stroke
				(width 0.1)
				(type default)
			)
			(layer "F.Fab")
		)
		(fp_line
			(start 0.67945 -0.3048)
			(end 0.67945 0.3048)
			(stroke
				(width 0.1)
				(type default)
			)
			(layer "F.Fab")
		)
		(fp_line
			(start -0.67945 -0.305054)
			(end -0.12065 -0.305054)
			(stroke
				(width 0.1)
				(type default)
			)
			(layer "F.Fab")
		)
		(fp_line
			(start -0.12065 -0.305054)
			(end -0.12065 -0.2794)
			(stroke
				(width 0.1)
				(type default)
			)
			(layer "F.Fab")
		)
		(pad "1" smd circle
			(at -0.40005 0 270)
			(size 0 0)
			(layers "F.Cu" "F.Mask" "F.Paste")
			(net "SW_P12V_AUX_PVDDCR_CPU1_P0_FLT")
		)
		(pad "2" smd circle
			(at 0.40005 0 270)
			(size 0 0)
			(layers "F.Cu" "F.Mask" "F.Paste")
			(net "GND")
		)
	)
	(footprint ""
		(layer "F.Cu")
		(at 335.315306 -416.899344 -90)
		(property "Reference" "C6521"
			(at 0 0 270)
			(layer "F.SilkS")
			(hide yes)
			(effects
				(font
					(size 1.27 1.27)
				)
			)
		)
		(property "Value" ""
			(at 0 0 270)
			(layer "F.Fab")
			(effects
				(font
					(size 1.27 1.27)
				)
			)
		)
		(duplicate_pad_numbers_are_jumpers no)
		(fp_line
			(start -0.299974 0.150114)
			(end -0.299974 -0.150114)
			(stroke
				(width 0.1)
				(type default)
			)
			(layer "F.Fab")
		)
		(fp_line
			(start 0.299974 0.150114)
			(end -0.299974 0.150114)
			(stroke
				(width 0.1)
				(type default)
			)
			(layer "F.Fab")
		)
		(fp_line
			(start -0.299974 -0.150114)
			(end 0.299974 -0.150114)
			(stroke
				(width 0.1)
				(type default)
			)
			(layer "F.Fab")
		)
		(fp_line
			(start 0.299974 -0.150114)
			(end 0.299974 0.150114)
			(stroke
				(width 0.1)
				(type default)
			)
			(layer "F.Fab")
		)
		(pad "1" smd rect
			(at -0.2667 0 270)
			(size 0.3048 0.381)
			(layers "F.Cu" "F.Mask" "F.Paste")
			(net "P5E_CPU0_P0_TX_BUF_C_DP<10>")
		)
		(pad "2" smd rect
			(at 0.2667 0 270)
			(size 0.3048 0.381)
			(layers "F.Cu" "F.Mask" "F.Paste")
			(net "P5E_CPU0_P0_TX_BUF_DP<10>")
		)
	)
	(footprint ""
		(layer "F.Cu")
		(at 426.687488 -332.63586 -90)
		(property "Reference" "PC230"
			(at -4.97078 -12.749276 90)
			(unlocked yes)
			(layer "F.SilkS")
			(effects
				(font
					(size 0.7874 0.5842)
					(thickness 0.1524)
				)
				(justify left)
			)
		)
		(property "Value" ""
			(at 0 0 270)
			(layer "F.Fab")
			(effects
				(font
					(size 1.27 1.27)
				)
			)
		)
		(duplicate_pad_numbers_are_jumpers no)
		(fp_line
			(start -1.988058 2.750058)
			(end 2.750058 2.750058)
			(stroke
				(width 0.1524)
				(type default)
			)
			(layer "F.SilkS")
		)
		(fp_line
			(start 2.750058 2.750058)
			(end 2.750058 0.9398)
			(stroke
				(width 0.1524)
				(type default)
			)
			(layer "F.SilkS")
		)
		(fp_line
			(start -2.750058 1.988058)
			(end -1.988058 2.750058)
			(stroke
				(width 0.1524)
				(type default)
			)
			(layer "F.SilkS")
		)
		(fp_line
			(start -2.750058 0.9398)
			(end -2.750058 1.988058)
			(stroke
				(width 0.1524)
				(type default)
			)
			(layer "F.SilkS")
		)
		(fp_line
			(start 2.750058 -0.9398)
			(end 2.750058 -2.750058)
			(stroke
				(width 0.1524)
				(type default)
			)
			(layer "F.SilkS")
		)
		(fp_line
			(start -2.750058 -1.988058)
			(end -2.750058 -0.9398)
			(stroke
				(width 0.1524)
				(type default)
			)
			(layer "F.SilkS")
		)
		(fp_line
			(start -1.988058 -2.750058)
			(end -2.750058 -1.988058)
			(stroke
				(width 0.1524)
				(type default)
			)
			(layer "F.SilkS")
		)
		(fp_line
			(start 2.750058 -2.750058)
			(end -1.988058 -2.750058)
			(stroke
				(width 0.1524)
				(type default)
			)
			(layer "F.SilkS")
		)
		(fp_line
			(start -2.750058 2.750058)
			(end 2.750058 2.750058)
			(stroke
				(width 0.1)
				(type default)
			)
			(layer "F.Fab")
		)
		(fp_line
			(start 2.750058 2.750058)
			(end 2.750058 -2.750058)
			(stroke
				(width 0.1)
				(type default)
			)
			(layer "F.Fab")
		)
		(fp_line
			(start -2.750058 -2.750058)
			(end -2.750058 2.750058)
			(stroke
				(width 0.1)
				(type default)
			)
			(layer "F.Fab")
		)
		(fp_line
			(start 2.750058 -2.750058)
			(end -2.750058 -2.750058)
			(stroke
				(width 0.1)
				(type default)
			)
			(layer "F.Fab")
		)
		(pad "1" smd rect
			(at -2.199894 0)
			(size 1.6002 3.0226)
			(layers "F.Cu" "F.Mask" "F.Paste")
			(net "PVDD11_S3_P0")
		)
		(pad "2" smd rect
			(at 2.199894 0)
			(size 1.6002 3.0226)
			(layers "F.Cu" "F.Mask" "F.Paste")
			(net "GND")
		)
	)
)
